(kicad_pcb
	(version 20241229)
	(generator "pcbnew")
	(generator_version "9.0")
	(general
		(thickness 1.62)
		(legacy_teardrops no)
	)
	(paper "A3")
	(title_block
		(title "COM Express 7 Baseboard")
		(date "2025-02-04")
		(rev "1.1.2")
		(company "Antmicro Ltd")
		(comment 1 "www.antmicro.com")
		(comment 9 "footprints 16-19 of 802")
	)
	(layers
		(0 "F.Cu" signal)
		(4 "In1.Cu" signal)
		(6 "In2.Cu" signal)
		(8 "In3.Cu" signal)
		(10 "In4.Cu" signal)
		(12 "In5.Cu" signal)
		(14 "In6.Cu" signal)
		(2 "B.Cu" signal)
		(9 "F.Adhes" user "F.Adhesive")
		(11 "B.Adhes" user "B.Adhesive")
		(13 "F.Paste" user)
		(15 "B.Paste" user)
		(5 "F.SilkS" user "F.Silkscreen")
		(7 "B.SilkS" user "B.Silkscreen")
		(1 "F.Mask" user)
		(3 "B.Mask" user)
		(17 "Dwgs.User" user "User.Drawings")
		(19 "Cmts.User" user "User.Comments")
		(21 "Eco1.User" user "User.Eco1")
		(23 "Eco2.User" user "User.Eco2")
		(25 "Edge.Cuts" user)
		(27 "Margin" user)
		(31 "F.CrtYd" user "F.Courtyard")
		(29 "B.CrtYd" user "B.Courtyard")
		(35 "F.Fab" user)
		(33 "B.Fab" user)
	)
	(footprint "antmicro-footprints:R_0402_1005Metric"
		(layer "F.Cu")
		(at 122.05 91.96)
		(descr "Resistor SMD 0402")
		(tags "resistor SMD 0402")
		(property "Reference" "R19"
			(at 0.75 0.45 0)
			(layer "F.SilkS")
			(effects
				(font
					(size 0.7 0.7)
					(thickness 0.15)
				)
				(justify left bottom)
			)
		)
		(property "Value" "R_10k_0402"
			(at -1.011843 1.772047 0)
			(layer "F.Fab")
			(effects
				(font
					(size 0.7 0.7)
					(thickness 0.15)
				)
				(justify left bottom)
			)
		)
		(property "Datasheet" "https://www.bourns.com/docs/product-datasheets/cr.pdf"
			(at 0 0 0)
			(layer "F.Fab")
			(hide yes)
			(effects
				(font
					(size 1.27 1.27)
					(thickness 0.15)
				)
			)
		)
		(property "Author" "Antmicro"
			(at 0 0 0)
			(layer "F.Fab")
			(hide yes)
			(effects
				(font
					(size 1 1)
					(thickness 0.15)
				)
			)
		)
		(property "License" "Apache-2.0"
			(at 0 0 0)
			(layer "F.Fab")
			(hide yes)
			(effects
				(font
					(size 1 1)
					(thickness 0.15)
				)
			)
		)
		(property "MPN" "CR0402-FX-1002GLF"
			(at 0 0 0)
			(layer "F.Fab")
			(hide yes)
			(effects
				(font
					(size 1 1)
					(thickness 0.15)
				)
			)
		)
		(property "Manufacturer" "Bourns"
			(at 0 0 0)
			(layer "F.Fab")
			(hide yes)
			(effects
				(font
					(size 1 1)
					(thickness 0.15)
				)
			)
		)
		(property "Public" "False"
			(at 0 0 0)
			(layer "F.Fab")
			(hide yes)
			(effects
				(font
					(size 1 1)
					(thickness 0.15)
				)
			)
		)
		(property "Tolerance" "1%"
			(at 0 0 0)
			(layer "F.Fab")
			(hide yes)
			(effects
				(font
					(size 1 1)
					(thickness 0.15)
				)
			)
		)
		(property "Val" "10k"
			(at 0 0 0)
			(layer "F.Fab")
			(hide yes)
			(effects
				(font
					(size 1 1)
					(thickness 0.15)
				)
			)
		)
		(sheetname "2xUSB3.0+RJ45")
		(sheetfile "usb3+rj45.kicad_sch")
		(attr smd dnp)
		(fp_rect
			(start -0.925 -0.47)
			(end 0.925 0.47)
			(stroke
				(width 0.05)
				(type default)
			)
			(fill no)
			(layer "F.CrtYd")
		)
		(fp_rect
			(start -0.5 -0.25)
			(end 0.5 0.25)
			(stroke
				(width 0.15)
				(type solid)
			)
			(fill no)
			(layer "F.Fab")
		)
		(pad "1" smd roundrect
			(at -0.48 0)
			(size 0.59 0.64)
			(layers "F.Cu" "F.Mask" "F.Paste")
			(roundrect_rratio 0.25)
			(net 554 "/2xUSB3.0+RJ45/FLG_2B")
			(pintype "passive")
			(teardrops
				(best_length_ratio 0.2)
				(max_length 1)
				(best_width_ratio 0.9)
				(max_width 2)
				(curved_edges yes)
				(filter_ratio 0.9)
				(enabled yes)
				(allow_two_segments yes)
				(prefer_zone_connections yes)
			)
		)
		(pad "2" smd roundrect
			(at 0.48 0)
			(size 0.59 0.64)
			(layers "F.Cu" "F.Mask" "F.Paste")
			(roundrect_rratio 0.25)
			(net 2 "+3V3")
			(pintype "passive")
			(teardrops
				(best_length_ratio 0.2)
				(max_length 1)
				(best_width_ratio 0.9)
				(max_width 2)
				(curved_edges yes)
				(filter_ratio 0.9)
				(enabled yes)
				(allow_two_segments yes)
				(prefer_zone_connections yes)
			)
		)
	)
	(footprint "antmicro-footprints:Choke_0805_2012Metric"
		(layer "F.Cu")
		(at 127.25 105.5 180)
		(property "Reference" "T2"
			(at 1.6 -1.85 0)
			(unlocked yes)
			(layer "F.SilkS")
			(effects
				(font
					(size 0.7 0.7)
					(thickness 0.15)
				)
				(justify left bottom)
			)
		)
		(property "Value" "Choke_SRF2012A-801Y"
			(at 0 -7 180)
			(unlocked yes)
			(layer "F.Fab")
			(effects
				(font
					(size 0.7 0.7)
					(thickness 0.15)
				)
				(justify left bottom)
			)
		)
		(property "Datasheet" "https://www.bourns.com/docs/product-datasheets/srf2012a-801y.pdf"
			(at 0 0 180)
			(layer "F.Fab")
			(hide yes)
			(effects
				(font
					(size 1.27 1.27)
					(thickness 0.15)
				)
			)
		)
		(property "Author" "Antmicro"
			(at 254.5 211 0)
			(layer "F.Fab")
			(hide yes)
			(effects
				(font
					(size 1 1)
					(thickness 0.15)
				)
			)
		)
		(property "IMax" "0.3 A"
			(at 254.5 211 0)
			(layer "F.Fab")
			(hide yes)
			(effects
				(font
					(size 1 1)
					(thickness 0.15)
				)
			)
		)
		(property "License" "Apache-2.0"
			(at 254.5 211 0)
			(layer "F.Fab")
			(hide yes)
			(effects
				(font
					(size 1 1)
					(thickness 0.15)
				)
			)
		)
		(property "MPN" "SRF2012A-801Y"
			(at 254.5 211 0)
			(layer "F.Fab")
			(hide yes)
			(effects
				(font
					(size 1 1)
					(thickness 0.15)
				)
			)
		)
		(property "Manufacturer" "Bourns"
			(at 254.5 211 0)
			(layer "F.Fab")
			(hide yes)
			(effects
				(font
					(size 1 1)
					(thickness 0.15)
				)
			)
		)
		(property "Public" "False"
			(at 254.5 211 0)
			(layer "F.Fab")
			(hide yes)
			(effects
				(font
					(size 1 1)
					(thickness 0.15)
				)
			)
		)
		(property ki_fp_filters "IND_ACM9070_TDK")
		(sheetname "2xUSB3.0+RJ45")
		(sheetfile "usb3+rj45.kicad_sch")
		(attr smd)
		(fp_rect
			(start -1.5 -0.9)
			(end 1.5 0.9)
			(stroke
				(width 0.05)
				(type solid)
			)
			(fill no)
			(layer "F.CrtYd")
		)
		(pad "1" smd roundrect
			(at -0.96 -0.46 180)
			(size 0.675 0.475)
			(layers "F.Cu" "F.Mask" "F.Paste")
			(roundrect_rratio 0.25)
			(net 691 "/2xUSB3.0+RJ45/DB_FL+")
			(pinfunction "1")
			(pintype "passive")
			(teardrops
				(best_length_ratio 0.2)
				(max_length 1)
				(best_width_ratio 0.9)
				(max_width 2)
				(curved_edges yes)
				(filter_ratio 0.9)
				(enabled yes)
				(allow_two_segments yes)
				(prefer_zone_connections yes)
			)
		)
		(pad "2" smd roundrect
			(at 0.96 -0.46 180)
			(size 0.675 0.475)
			(layers "F.Cu" "F.Mask" "F.Paste")
			(roundrect_rratio 0.25)
			(net 148 "/2xUSB3.0+RJ45/DB+")
			(pinfunction "2")
			(pintype "passive")
			(teardrops
				(best_length_ratio 0.2)
				(max_length 1)
				(best_width_ratio 0.9)
				(max_width 2)
				(curved_edges yes)
				(filter_ratio 0.9)
				(enabled yes)
				(allow_two_segments yes)
				(prefer_zone_connections yes)
			)
		)
		(pad "3" smd roundrect
			(at 0.96 0.46 180)
			(size 0.675 0.475)
			(layers "F.Cu" "F.Mask" "F.Paste")
			(roundrect_rratio 0.25)
			(net 151 "/2xUSB3.0+RJ45/DB-")
			(pinfunction "3")
			(pintype "passive")
			(teardrops
				(best_length_ratio 0.2)
				(max_length 1)
				(best_width_ratio 0.9)
				(max_width 2)
				(curved_edges yes)
				(filter_ratio 0.9)
				(enabled yes)
				(allow_two_segments yes)
				(prefer_zone_connections yes)
			)
		)
		(pad "4" smd roundrect
			(at -0.96 0.46 180)
			(size 0.675 0.475)
			(layers "F.Cu" "F.Mask" "F.Paste")
			(roundrect_rratio 0.25)
			(net 692 "/2xUSB3.0+RJ45/DB_FL-")
			(pinfunction "4")
			(pintype "passive")
			(teardrops
				(best_length_ratio 0.2)
				(max_length 1)
				(best_width_ratio 0.9)
				(max_width 2)
				(curved_edges yes)
				(filter_ratio 0.9)
				(enabled yes)
				(allow_two_segments yes)
				(prefer_zone_connections yes)
			)
		)
	)
	(footprint "antmicro-footprints:R_0402_1005Metric"
		(layer "F.Cu")
		(at 177.52 108.66 180)
		(descr "Resistor SMD 0402")
		(tags "resistor SMD 0402")
		(property "Reference" "R124"
			(at 0.82 -0.5 0)
			(layer "F.SilkS")
			(effects
				(font
					(size 0.7 0.7)
					(thickness 0.15)
				)
				(justify right bottom)
			)
		)
		(property "Value" "R_0R_0402"
			(at -1.011843 1.772047 0)
			(layer "F.Fab")
			(effects
				(font
					(size 0.7 0.7)
					(thickness 0.15)
				)
				(justify right bottom)
			)
		)
		(property "Datasheet" "https://industrial.panasonic.com/cdbs/www-data/pdf/RDA0000/AOA0000C301.pdf"
			(at 0 0 180)
			(layer "F.Fab")
			(hide yes)
			(effects
				(font
					(size 1.27 1.27)
					(thickness 0.15)
				)
			)
		)
		(property "Author" "Antmicro"
			(at 355.04 217.32 0)
			(layer "F.Fab")
			(hide yes)
			(effects
				(font
					(size 1 1)
					(thickness 0.15)
				)
			)
		)
		(property "Current" "1A"
			(at 355.04 217.32 0)
			(layer "F.Fab")
			(hide yes)
			(effects
				(font
					(size 1 1)
					(thickness 0.15)
				)
			)
		)
		(property "License" "Apache-2.0"
			(at 355.04 217.32 0)
			(layer "F.Fab")
			(hide yes)
			(effects
				(font
					(size 1 1)
					(thickness 0.15)
				)
			)
		)
		(property "MPN" "ERJ2GE0R00X"
			(at 355.04 217.32 0)
			(layer "F.Fab")
			(hide yes)
			(effects
				(font
					(size 1 1)
					(thickness 0.15)
				)
			)
		)
		(property "Manufacturer" "Panasonic"
			(at 355.04 217.32 0)
			(layer "F.Fab")
			(hide yes)
			(effects
				(font
					(size 1 1)
					(thickness 0.15)
				)
			)
		)
		(property "Public" "False"
			(at 355.04 217.32 0)
			(layer "F.Fab")
			(hide yes)
			(effects
				(font
					(size 1 1)
					(thickness 0.15)
				)
			)
		)
		(property "Tolerance" ""
			(at 355.04 217.32 0)
			(layer "F.Fab")
			(hide yes)
			(effects
				(font
					(size 1 1)
					(thickness 0.15)
				)
			)
		)
		(property "Val" "0R"
			(at 355.04 217.32 0)
			(layer "F.Fab")
			(hide yes)
			(effects
				(font
					(size 1 1)
					(thickness 0.15)
				)
			)
		)
		(sheetname "M.2 key M #1")
		(sheetfile "m2keym_low.kicad_sch")
		(attr smd)
		(fp_rect
			(start -0.925 -0.47)
			(end 0.925 0.47)
			(stroke
				(width 0.05)
				(type default)
			)
			(fill no)
			(layer "F.CrtYd")
		)
		(fp_rect
			(start -0.5 -0.25)
			(end 0.5 0.25)
			(stroke
				(width 0.15)
				(type solid)
			)
			(fill no)
			(layer "F.Fab")
		)
		(pad "1" smd roundrect
			(at -0.48 0 180)
			(size 0.59 0.64)
			(layers "F.Cu" "F.Mask" "F.Paste")
			(roundrect_rratio 0.25)
			(net 926 "Net-(J5-SUSCLK)")
			(pintype "passive")
			(teardrops
				(best_length_ratio 0.2)
				(max_length 1)
				(best_width_ratio 0.9)
				(max_width 2)
				(curved_edges yes)
				(filter_ratio 0.9)
				(enabled yes)
				(allow_two_segments yes)
				(prefer_zone_connections yes)
			)
		)
		(pad "2" smd roundrect
			(at 0.48 0 180)
			(size 0.59 0.64)
			(layers "F.Cu" "F.Mask" "F.Paste")
			(roundrect_rratio 0.25)
			(net 587 "/M.2 key E/SUSCLK")
			(pintype "passive")
			(teardrops
				(best_length_ratio 0.2)
				(max_length 1)
				(best_width_ratio 0.9)
				(max_width 2)
				(curved_edges yes)
				(filter_ratio 0.9)
				(enabled yes)
				(allow_two_segments yes)
				(prefer_zone_connections yes)
			)
		)
	)
	(footprint "antmicro-footprints:C_Pol_EIA-B"
		(layer "F.Cu")
		(at 308.825 100.64)
		(property "Reference" "C52"
			(at 2.275 0.47 0)
			(layer "F.SilkS")
			(effects
				(font
					(size 0.7 0.7)
					(thickness 0.15)
				)
				(justify left bottom)
			)
		)
		(property "Value" "C_Pol_100u_10V_KEMET-T520-B"
			(at 0 2.85 0)
			(layer "F.Fab")
			(effects
				(font
					(size 0.7 0.7)
					(thickness 0.15)
				)
				(justify left bottom)
			)
		)
		(property "Datasheet" "https://www.kemet.com/en/us/capacitors/product/T520B107M010ATE070.html"
			(at 0 0 0)
			(layer "F.Fab")
			(hide yes)
			(effects
				(font
					(size 1.27 1.27)
					(thickness 0.15)
				)
			)
		)
		(property "Author" "Antmicro"
			(at 0 0 0)
			(layer "F.Fab")
			(hide yes)
			(effects
				(font
					(size 1 1)
					(thickness 0.15)
				)
			)
		)
		(property "Dielectric" "template_dielectric"
			(at 0 0 0)
			(layer "F.Fab")
			(hide yes)
			(effects
				(font
					(size 1 1)
					(thickness 0.15)
				)
			)
		)
		(property "License" "Apache-2.0"
			(at 0 0 0)
			(layer "F.Fab")
			(hide yes)
			(effects
				(font
					(size 1 1)
					(thickness 0.15)
				)
			)
		)
		(property "MPN" "T520B107M010ATE070"
			(at 0 0 0)
			(layer "F.Fab")
			(hide yes)
			(effects
				(font
					(size 1 1)
					(thickness 0.15)
				)
			)
		)
		(property "Manufacturer" "KEMET"
			(at 0 0 0)
			(layer "F.Fab")
			(hide yes)
			(effects
				(font
					(size 1 1)
					(thickness 0.15)
				)
			)
		)
		(property "Public" "False"
			(at 0 0 0)
			(layer "F.Fab")
			(hide yes)
			(effects
				(font
					(size 1 1)
					(thickness 0.15)
				)
			)
		)
		(property "Val" "100u"
			(at 0 0 0)
			(layer "F.Fab")
			(hide yes)
			(effects
				(font
					(size 1 1)
					(thickness 0.15)
				)
			)
		)
		(property "Voltage" "10V"
			(at 0 0 0)
			(layer "F.Fab")
			(hide yes)
			(effects
				(font
					(size 1 1)
					(thickness 0.15)
				)
			)
		)
		(sheetname "Power")
		(sheetfile "power.kicad_sch")
		(attr smd)
		(fp_line
			(start -2.521 -1.676)
			(end -2.123 -1.676)
			(stroke
				(width 0.15)
				(type solid)
			)
			(layer "F.SilkS")
		)
		(fp_line
			(start -2.325 -1.475)
			(end -2.325 -1.878)
			(stroke
				(width 0.15)
				(type solid)
			)
			(layer "F.SilkS")
		)
		(fp_line
			(start -1.8 -1.6)
			(end 1.8 -1.6)
			(stroke
				(width 0.15)
				(type solid)
			)
			(layer "F.SilkS")
		)
		(fp_line
			(start -1.8 -1.3)
			(end -1.8 -1.6)
			(stroke
				(width 0.15)
				(type solid)
			)
			(layer "F.SilkS")
		)
		(fp_line
			(start -1.8 1.3)
			(end -1.8 1.6)
			(stroke
				(width 0.15)
				(type solid)
			)
			(layer "F.SilkS")
		)
		(fp_line
			(start 1.8 -1.3)
			(end 1.8 -1.6)
			(stroke
				(width 0.15)
				(type solid)
			)
			(layer "F.SilkS")
		)
		(fp_line
			(start 1.8 1.3)
			(end 1.8 1.6)
			(stroke
				(width 0.15)
				(type solid)
			)
			(layer "F.SilkS")
		)
		(fp_line
			(start 1.8 1.6)
			(end -1.8 1.6)
			(stroke
				(width 0.15)
				(type solid)
			)
			(layer "F.SilkS")
		)
		(fp_line
			(start -2.411 -1.35)
			(end -2.41 1.35)
			(stroke
				(width 0.05)
				(type solid)
			)
			(layer "F.CrtYd")
		)
		(fp_line
			(start -1.97 -1.75)
			(end -1.97 -1.35)
			(stroke
				(width 0.05)
				(type solid)
			)
			(layer "F.CrtYd")
		)
		(fp_line
			(start -1.97 -1.35)
			(end -2.41 -1.35)
			(stroke
				(width 0.05)
				(type solid)
			)
			(layer "F.CrtYd")
		)
		(fp_line
			(start -1.97 1.35)
			(end -2.41 1.35)
			(stroke
				(width 0.05)
				(type solid)
			)
			(layer "F.CrtYd")
		)
		(fp_line
			(start -1.97 1.35)
			(end -1.97 1.75)
			(stroke
				(width 0.05)
				(type solid)
			)
			(layer "F.CrtYd")
		)
		(fp_line
			(start 1.959 -1.75)
			(end -1.97 -1.75)
			(stroke
				(width 0.05)
				(type solid)
			)
			(layer "F.CrtYd")
		)
		(fp_line
			(start 1.959 -1.75)
			(end 1.959 -1.35)
			(stroke
				(width 0.05)
				(type solid)
			)
			(layer "F.CrtYd")
		)
		(fp_line
			(start 1.96 1.35)
			(end 1.96 1.75)
			(stroke
				(width 0.05)
				(type solid)
			)
			(layer "F.CrtYd")
		)
		(fp_line
			(start 1.96 1.75)
			(end -1.97 1.75)
			(stroke
				(width 0.05)
				(type solid)
			)
			(layer "F.CrtYd")
		)
		(fp_line
			(start 2.399 -1.35)
			(end 1.959 -1.35)
			(stroke
				(width 0.05)
				(type solid)
			)
			(layer "F.CrtYd")
		)
		(fp_line
			(start 2.399 -1.35)
			(end 2.4 1.35)
			(stroke
				(width 0.05)
				(type solid)
			)
			(layer "F.CrtYd")
		)
		(fp_line
			(start 2.4 1.35)
			(end 1.96 1.35)
			(stroke
				(width 0.05)
				(type solid)
			)
			(layer "F.CrtYd")
		)
		(fp_line
			(start -1.7 1.324)
			(end -1.551 1.475)
			(stroke
				(width 0.15)
				(type solid)
			)
			(layer "F.Fab")
		)
		(fp_rect
			(start -1.72 -1.5)
			(end 1.719 1.499)
			(stroke
				(width 0.15)
				(type solid)
			)
			(fill no)
			(layer "F.Fab")
		)
		(pad "1" smd roundrect
			(at -1.551 0)
			(size 1.2 2.2)
			(layers "F.Cu" "F.Mask" "F.Paste")
			(roundrect_rratio 0.1)
			(net 71 "Net-(U49-IN+)")
			(pintype "passive")
			(teardrops
				(best_length_ratio 0.2)
				(max_length 1)
				(best_width_ratio 0.9)
				(max_width 2)
				(curved_edges yes)
				(filter_ratio 0.9)
				(enabled yes)
				(allow_two_segments yes)
				(prefer_zone_connections yes)
			)
		)
		(pad "2" smd roundrect
			(at 1.55 0)
			(size 1.2 2.2)
			(layers "F.Cu" "F.Mask" "F.Paste")
			(roundrect_rratio 0.1)
			(net 1 "GND")
			(pintype "passive")
			(teardrops
				(best_length_ratio 0.2)
				(max_length 1)
				(best_width_ratio 0.9)
				(max_width 2)
				(curved_edges yes)
				(filter_ratio 0.9)
				(enabled yes)
				(allow_two_segments yes)
				(prefer_zone_connections yes)
			)
		)
	)
)
